(kicad_pcb
	(version 20260206)
	(generator "pcbnew")
	(generator_version "10.0")
	(general
		(thickness 1.6)
		(legacy_teardrops no)
	)
	(paper "A4")
	(title_block
		(title "Bryce Canyon_SCC_16316-1_OCP.brd")
		(comment 1 "Bryce Canyon / footprints 759-767 of 1561")
	)
	(layers
		(0 "F.Cu" signal "TOP")
		(4 "In1.Cu" signal "L2GND")
		(6 "In2.Cu" signal "L3")
		(8 "In3.Cu" signal "L4VCC")
		(10 "In4.Cu" signal "L5VCC")
		(12 "In5.Cu" signal "L6")
		(14 "In6.Cu" signal "L7GND")
		(2 "B.Cu" signal "BOTTOM")
		(9 "F.Adhes" user "F.Adhesive")
		(11 "B.Adhes" user "B.Adhesive")
		(13 "F.Paste" user "Package Geometry/Pastemask Top")
		(15 "B.Paste" user "Package Geometry/Pastemask Bottom")
		(5 "F.SilkS" user "Ref Des/Silkscreen Top")
		(7 "B.SilkS" user "Ref Des/Silkscreen Bottom")
		(1 "F.Mask" user "Board Geometry/Soldermask Top")
		(3 "B.Mask" user "Board Geometry/Soldermask Bottom")
		(17 "Dwgs.User" user "User.Drawings")
		(19 "Cmts.User" user "User.Comments")
		(21 "Eco1.User" user "User.Eco1")
		(23 "Eco2.User" user "User.Eco2")
		(25 "Edge.Cuts" user "Board Geometry/Outline")
		(27 "Margin" user)
		(31 "F.CrtYd" user "Package Geometry/Place Bound Top")
		(29 "B.CrtYd" user "Package Geometry/Place Bound Bottom")
		(35 "F.Fab" user "Ref Des/Assembly Top")
		(33 "B.Fab" user "Ref Des/Assembly Bottom")
	)
	(footprint ""
		(layer "F.Cu")
		(at 47.0662 -27.94 90)
		(property "Reference" "R477"
			(at 0 0 90)
			(layer "F.SilkS")
			(hide yes)
			(effects
				(font
					(size 1.27 1.27)
				)
			)
		)
		(property "Value" "0R2F-1-GP"
			(at 0.064008 -3.993896 90)
			(unlocked yes)
			(layer "F.Fab")
			(hide yes)
			(effects
				(font
					(size 1.016 1.016)
					(thickness 0.1524)
				)
			)
		)
		(property "Device Type" "R402H16"
			(at 0.064008 -5.517896 90)
			(unlocked yes)
			(layer "F.Fab")
			(hide yes)
			(effects
				(font
					(size 1.016 1.016)
					(thickness 0.1524)
				)
			)
		)
		(duplicate_pad_numbers_are_jumpers no)
		(fp_line
			(start 0.508 -0.9398)
			(end -0.508 -0.9398)
			(stroke
				(width 0.1524)
				(type default)
			)
			(layer "F.SilkS")
		)
		(fp_line
			(start -0.508 -0.9398)
			(end -0.508 0.9398)
			(stroke
				(width 0.1524)
				(type default)
			)
			(layer "F.SilkS")
		)
		(fp_rect
			(start -0.508 0.9398)
			(end 0.508 -0.9398)
			(stroke
				(width 0)
				(type default)
			)
			(fill no)
			(layer "F.CrtYd")
		)
		(fp_rect
			(start -0.508 0.9398)
			(end 0.508 -0.9398)
			(stroke
				(width 0)
				(type default)
			)
			(fill no)
			(layer "F.Fab")
		)
		(pad "1" smd custom
			(at 0 -0.4445 90)
			(size 0.1397 0.1397)
			(layers "F.Cu" "F.Mask" "F.Paste")
			(net "P0V9_GSNS")
			(options
				(clearance outline)
				(anchor circle)
			)
			(primitives
				(gr_poly
					(pts
						(arc
							(start -0.1778 -0.2794)
							(mid -0.249642 -0.249642)
							(end -0.2794 -0.1778)
						)
						(arc
							(start -0.2794 0.1778)
							(mid -0.249642 0.249642)
							(end -0.1778 0.2794)
						)
						(arc
							(start 0.1778 0.2794)
							(mid 0.249642 0.249642)
							(end 0.2794 0.1778)
						)
						(arc
							(start 0.2794 -0.1778)
							(mid 0.249642 -0.249642)
							(end 0.1778 -0.2794)
						)
					)
					(width 0)
					(fill yes)
				)
			)
		)
		(pad "2" smd custom
			(at 0 0.4445 90)
			(size 0.1397 0.1397)
			(layers "F.Cu" "F.Mask" "F.Paste")
			(net "GND")
			(options
				(clearance outline)
				(anchor circle)
			)
			(primitives
				(gr_poly
					(pts
						(arc
							(start -0.1778 -0.2794)
							(mid -0.249642 -0.249642)
							(end -0.2794 -0.1778)
						)
						(arc
							(start -0.2794 0.1778)
							(mid -0.249642 0.249642)
							(end -0.1778 0.2794)
						)
						(arc
							(start 0.1778 0.2794)
							(mid 0.249642 0.249642)
							(end 0.2794 0.1778)
						)
						(arc
							(start 0.2794 -0.1778)
							(mid 0.249642 -0.249642)
							(end 0.1778 -0.2794)
						)
					)
					(width 0)
					(fill yes)
				)
			)
		)
	)
	(footprint ""
		(layer "F.Cu")
		(at 158.5087 -88.6206 -90)
		(property "Reference" "R329"
			(at 0 0 270)
			(layer "F.SilkS")
			(hide yes)
			(effects
				(font
					(size 1.27 1.27)
				)
			)
		)
		(property "Value" "4K7R2F-GP"
			(at 0.064008 -3.993896 270)
			(unlocked yes)
			(layer "F.Fab")
			(hide yes)
			(effects
				(font
					(size 1.016 1.016)
					(thickness 0.1524)
				)
			)
		)
		(property "Device Type" "R402H16"
			(at 0.064008 -5.517896 270)
			(unlocked yes)
			(layer "F.Fab")
			(hide yes)
			(effects
				(font
					(size 1.016 1.016)
					(thickness 0.1524)
				)
			)
		)
		(duplicate_pad_numbers_are_jumpers no)
		(fp_line
			(start -0.508 -0.9398)
			(end -0.508 0.9398)
			(stroke
				(width 0.1524)
				(type default)
			)
			(layer "F.SilkS")
		)
		(fp_line
			(start 0.508 -0.9398)
			(end -0.508 -0.9398)
			(stroke
				(width 0.1524)
				(type default)
			)
			(layer "F.SilkS")
		)
		(fp_rect
			(start -0.508 0.9398)
			(end 0.508 -0.9398)
			(stroke
				(width 0)
				(type default)
			)
			(fill no)
			(layer "F.CrtYd")
		)
		(fp_rect
			(start -0.508 0.9398)
			(end 0.508 -0.9398)
			(stroke
				(width 0)
				(type default)
			)
			(fill no)
			(layer "F.Fab")
		)
		(pad "1" smd custom
			(at 0 -0.4445 270)
			(size 0.1397 0.1397)
			(layers "F.Cu" "F.Mask" "F.Paste")
			(net "P3V3")
			(options
				(clearance outline)
				(anchor circle)
			)
			(primitives
				(gr_poly
					(pts
						(arc
							(start -0.1778 -0.2794)
							(mid -0.249642 -0.249642)
							(end -0.2794 -0.1778)
						)
						(arc
							(start -0.2794 0.1778)
							(mid -0.249642 0.249642)
							(end -0.1778 0.2794)
						)
						(arc
							(start 0.1778 0.2794)
							(mid 0.249642 0.249642)
							(end 0.2794 0.1778)
						)
						(arc
							(start 0.2794 -0.1778)
							(mid 0.249642 -0.249642)
							(end 0.1778 -0.2794)
						)
					)
					(width 0)
					(fill yes)
				)
			)
		)
		(pad "2" smd custom
			(at 0 0.4445 270)
			(size 0.1397 0.1397)
			(layers "F.Cu" "F.Mask" "F.Paste")
			(net "VOL_SEN1_ALERT")
			(options
				(clearance outline)
				(anchor circle)
			)
			(primitives
				(gr_poly
					(pts
						(arc
							(start -0.1778 -0.2794)
							(mid -0.249642 -0.249642)
							(end -0.2794 -0.1778)
						)
						(arc
							(start -0.2794 0.1778)
							(mid -0.249642 0.249642)
							(end -0.1778 0.2794)
						)
						(arc
							(start 0.1778 0.2794)
							(mid 0.249642 0.249642)
							(end 0.2794 0.1778)
						)
						(arc
							(start 0.2794 -0.1778)
							(mid 0.249642 -0.249642)
							(end 0.1778 -0.2794)
						)
					)
					(width 0)
					(fill yes)
				)
			)
		)
	)
	(footprint ""
		(layer "F.Cu")
		(at 202.47737 -74.997818 180)
		(property "Reference" "C349"
			(at 0 0 180)
			(layer "F.SilkS")
			(hide yes)
			(effects
				(font
					(size 1.27 1.27)
				)
			)
		)
		(property "Value" "SCD1U16V2KX-3GP"
			(at 1.1811 -2.7051 180)
			(unlocked yes)
			(layer "F.Fab")
			(hide yes)
			(effects
				(font
					(size 1.016 1.016)
					(thickness 0.1524)
				)
			)
		)
		(property "Device Type" "C402H22"
			(at 1.1811 -4.2291 180)
			(unlocked yes)
			(layer "F.Fab")
			(hide yes)
			(effects
				(font
					(size 1.016 1.016)
					(thickness 0.1524)
				)
			)
		)
		(duplicate_pad_numbers_are_jumpers no)
		(fp_rect
			(start -0.4318 0.9525)
			(end 0.4318 -0.9525)
			(stroke
				(width 0)
				(type default)
			)
			(fill no)
			(layer "F.CrtYd")
		)
		(fp_rect
			(start -0.4318 0.9525)
			(end 0.4318 -0.9525)
			(stroke
				(width 0)
				(type default)
			)
			(fill no)
			(layer "F.Fab")
		)
		(pad "1" smd custom
			(at 0 -0.4445 180)
			(size 0.1524 0.1524)
			(layers "F.Cu" "F.Mask" "F.Paste")
			(net "P1V8_C")
			(options
				(clearance outline)
				(anchor circle)
			)
			(primitives
				(gr_poly
					(pts
						(arc
							(start 0.3048 -0.2032)
							(mid 0.275042 -0.275042)
							(end 0.2032 -0.3048)
						)
						(arc
							(start -0.2032 -0.3048)
							(mid -0.275042 -0.275042)
							(end -0.3048 -0.2032)
						)
						(arc
							(start -0.3048 0.2032)
							(mid -0.275042 0.275042)
							(end -0.2032 0.3048)
						)
						(arc
							(start 0.2032 0.3048)
							(mid 0.275042 0.275042)
							(end 0.3048 0.2032)
						)
					)
					(width 0)
					(fill yes)
				)
			)
		)
		(pad "2" smd custom
			(at 0 0.4445 180)
			(size 0.1524 0.1524)
			(layers "F.Cu" "F.Mask" "F.Paste")
			(net "GND")
			(options
				(clearance outline)
				(anchor circle)
			)
			(primitives
				(gr_poly
					(pts
						(arc
							(start 0.3048 -0.2032)
							(mid 0.275042 -0.275042)
							(end 0.2032 -0.3048)
						)
						(arc
							(start -0.2032 -0.3048)
							(mid -0.275042 -0.275042)
							(end -0.3048 -0.2032)
						)
						(arc
							(start -0.3048 0.2032)
							(mid -0.275042 0.275042)
							(end -0.2032 0.3048)
						)
						(arc
							(start 0.2032 0.3048)
							(mid 0.275042 0.275042)
							(end 0.3048 0.2032)
						)
					)
					(width 0)
					(fill yes)
				)
			)
		)
	)
	(footprint ""
		(layer "F.Cu")
		(at 191.8462 -33.3121 -90)
		(property "Reference" "TP68"
			(at 0 0 270)
			(layer "F.SilkS")
			(hide yes)
			(effects
				(font
					(size 1.27 1.27)
				)
			)
		)
		(property "Value" "TPAD28-2-GP"
			(at -0.0127 -1.6637 270)
			(unlocked yes)
			(layer "F.Fab")
			(hide yes)
			(effects
				(font
					(size 1.016 1.016)
					(thickness 0.1524)
				)
			)
		)
		(property "Device Type" "TPAD28"
			(at -0.0127 -3.1877 270)
			(unlocked yes)
			(layer "F.Fab")
			(hide yes)
			(effects
				(font
					(size 1.016 1.016)
					(thickness 0.1524)
				)
			)
		)
		(duplicate_pad_numbers_are_jumpers no)
		(fp_poly
			(pts
				(arc
					(start 0 -0.3556)
					(mid 0 0.3556)
					(end 0 -0.3556)
				)
			)
			(stroke
				(width 0)
				(type default)
			)
			(fill no)
			(layer "F.CrtYd")
		)
		(fp_poly
			(pts
				(arc
					(start 0 -0.6096)
					(mid 0 0.6096)
					(end 0 -0.6096)
				)
			)
			(stroke
				(width 0)
				(type default)
			)
			(fill no)
			(layer "F.Fab")
		)
		(pad "1" smd circle
			(at 0 0 270)
			(size 0.7112 0.7112)
			(layers "F.Cu" "F.Mask" "F.Paste")
			(net "IOC_GPIO_15")
		)
	)
	(footprint ""
		(layer "B.Cu")
		(at 179.796694 -34.01822)
		(property "Reference" "TP132"
			(at 0 0 0)
			(layer "B.SilkS")
			(hide yes)
			(effects
				(font
					(size 1.27 1.27)
				)
				(justify mirror)
			)
		)
		(property "Value" "TPAD28-2-GP"
			(at 0.0127 -1.6637 0)
			(unlocked yes)
			(layer "B.Fab")
			(hide yes)
			(effects
				(font
					(size 1.016 1.016)
					(thickness 0.1524)
				)
				(justify mirror)
			)
		)
		(property "Device Type" "TPAD28"
			(at 0.0127 -3.1877 0)
			(unlocked yes)
			(layer "B.Fab")
			(hide yes)
			(effects
				(font
					(size 1.016 1.016)
					(thickness 0.1524)
				)
				(justify mirror)
			)
		)
		(duplicate_pad_numbers_are_jumpers no)
		(fp_poly
			(pts
				(arc
					(start 0.3556 0)
					(mid -0.3556 0)
					(end 0.3556 0)
				)
			)
			(stroke
				(width 0)
				(type default)
			)
			(fill no)
			(layer "B.CrtYd")
		)
		(fp_poly
			(pts
				(arc
					(start 0.6096 0)
					(mid -0.6096 0)
					(end 0.6096 0)
				)
			)
			(stroke
				(width 0)
				(type default)
			)
			(fill no)
			(layer "B.Fab")
		)
		(pad "1" smd circle
			(at 0 0 180)
			(size 0.7112 0.7112)
			(layers "B.Cu" "B.Mask" "B.Paste")
			(net "SYS_DBMODE0")
		)
	)
	(footprint ""
		(layer "B.Cu")
		(at 129.397252 -55.233824 90)
		(property "Reference" "C297"
			(at 0 0 90)
			(layer "B.SilkS")
			(hide yes)
			(effects
				(font
					(size 1.27 1.27)
				)
				(justify mirror)
			)
		)
		(property "Value" "SCD1U6D3V1KX-GP"
			(at 2.8321 -1.7399 90)
			(unlocked yes)
			(layer "B.Fab")
			(hide yes)
			(effects
				(font
					(size 1.016 1.016)
					(thickness 0.1524)
				)
				(justify mirror)
			)
		)
		(property "Device Type" "C0201H13"
			(at 2.8321 -3.2639 90)
			(unlocked yes)
			(layer "B.Fab")
			(hide yes)
			(effects
				(font
					(size 1.016 1.016)
					(thickness 0.1524)
				)
				(justify mirror)
			)
		)
		(duplicate_pad_numbers_are_jumpers no)
		(fp_rect
			(start 0.2794 0.6477)
			(end -0.2794 -0.6477)
			(stroke
				(width 0)
				(type default)
			)
			(fill no)
			(layer "B.CrtYd")
		)
		(fp_rect
			(start 0.2794 0.6477)
			(end -0.2794 -0.6477)
			(stroke
				(width 0)
				(type default)
			)
			(fill no)
			(layer "B.Fab")
		)
		(pad "1" smd custom
			(at 0 -0.2794 270)
			(size 0.0762 0.0762)
			(layers "B.Cu" "B.Mask" "B.Paste")
			(net "GB_VDDA")
			(options
				(clearance outline)
				(anchor circle)
			)
			(primitives
				(gr_poly
					(pts
						(arc
							(start 0.1524 0.127)
							(mid 0.137521 0.162921)
							(end 0.1016 0.1778)
						)
						(arc
							(start -0.1016 0.1778)
							(mid -0.137521 0.162921)
							(end -0.1524 0.127)
						)
						(arc
							(start -0.1524 -0.127)
							(mid -0.137521 -0.162921)
							(end -0.1016 -0.1778)
						)
						(arc
							(start 0.1016 -0.1778)
							(mid 0.137521 -0.162921)
							(end 0.1524 -0.127)
						)
					)
					(width 0)
					(fill yes)
				)
			)
		)
		(pad "2" smd custom
			(at 0 0.2794 270)
			(size 0.0762 0.0762)
			(layers "B.Cu" "B.Mask" "B.Paste")
			(net "GND")
			(options
				(clearance outline)
				(anchor circle)
			)
			(primitives
				(gr_poly
					(pts
						(arc
							(start 0.1524 0.127)
							(mid 0.137521 0.162921)
							(end 0.1016 0.1778)
						)
						(arc
							(start -0.1016 0.1778)
							(mid -0.137521 0.162921)
							(end -0.1524 0.127)
						)
						(arc
							(start -0.1524 -0.127)
							(mid -0.137521 -0.162921)
							(end -0.1016 -0.1778)
						)
						(arc
							(start 0.1016 -0.1778)
							(mid 0.137521 -0.162921)
							(end 0.1524 -0.127)
						)
					)
					(width 0)
					(fill yes)
				)
			)
		)
	)
	(footprint ""
		(layer "B.Cu")
		(at 11.43 -52.1208)
		(property "Reference" "P1"
			(at 0 0 0)
			(layer "B.SilkS")
			(hide yes)
			(effects
				(font
					(size 1.27 1.27)
				)
				(justify mirror)
			)
		)
		(property "Value" "0R0603-PAD-2-GP-U"
			(at -2.1209 -0.1397 0)
			(unlocked yes)
			(layer "B.Fab")
			(hide yes)
			(effects
				(font
					(size 1.016 1.016)
					(thickness 0.1524)
				)
				(justify mirror)
			)
		)
		(property "Device Type" "0R0603-PAD-1-U"
			(at -2.1209 -1.6637 0)
			(unlocked yes)
			(layer "B.Fab")
			(hide yes)
			(effects
				(font
					(size 1.016 1.016)
					(thickness 0.1524)
				)
				(justify mirror)
			)
		)
		(duplicate_pad_numbers_are_jumpers no)
		(fp_rect
			(start 0.5842 1.3335)
			(end -0.5842 -1.3335)
			(stroke
				(width 0)
				(type default)
			)
			(fill no)
			(layer "B.CrtYd")
		)
		(fp_rect
			(start 0.5842 1.3335)
			(end -0.5842 -1.3335)
			(stroke
				(width 0)
				(type default)
			)
			(fill no)
			(layer "B.Fab")
		)
		(pad "1" smd custom
			(at 0 -0.762 180)
			(size 0.2159 0.2159)
			(layers "B.Cu" "B.Mask" "B.Paste")
			(net "AGND_CURRENT_MON")
			(options
				(clearance outline)
				(anchor circle)
			)
			(primitives
				(gr_poly
					(pts
						(arc
							(start -0.3302 0.5842)
							(mid -0.402042 0.554442)
							(end -0.4318 0.4826)
						)
						(arc
							(start -0.4318 -0.4826)
							(mid -0.402042 -0.554442)
							(end -0.3302 -0.5842)
						)
						(arc
							(start 0.3302 -0.5842)
							(mid 0.402042 -0.554442)
							(end 0.4318 -0.4826)
						)
						(arc
							(start 0.4318 0.4826)
							(mid 0.402042 0.554442)
							(end 0.3302 0.5842)
						)
					)
					(width 0)
					(fill yes)
				)
			)
		)
		(pad "2" smd custom
			(at 0 0.762 180)
			(size 0.2159 0.2159)
			(layers "B.Cu" "B.Mask" "B.Paste")
			(net "GND")
			(options
				(clearance outline)
				(anchor circle)
			)
			(primitives
				(gr_poly
					(pts
						(arc
							(start -0.4318 -0.4826)
							(mid -0.402042 -0.554442)
							(end -0.3302 -0.5842)
						)
						(arc
							(start 0.3302 -0.5842)
							(mid 0.402042 -0.554442)
							(end 0.4318 -0.4826)
						)
						(arc
							(start 0.4318 0.4826)
							(mid 0.402042 0.554442)
							(end 0.3302 0.5842)
						)
						(arc
							(start -0.3302 0.5842)
							(mid -0.402042 0.554442)
							(end -0.4318 0.4826)
						)
					)
					(width 0)
					(fill yes)
				)
			)
		)
	)
	(footprint ""
		(layer "B.Cu")
		(at 97.2058 -44.2214 180)
		(property "Reference" "C87"
			(at 0 0 0)
			(layer "B.SilkS")
			(hide yes)
			(effects
				(font
					(size 1.27 1.27)
				)
				(justify mirror)
			)
		)
		(property "Value" "SCD01U16V1KX-GP"
			(at 2.8321 -1.7399 180)
			(unlocked yes)
			(layer "B.Fab")
			(hide yes)
			(effects
				(font
					(size 1.016 1.016)
					(thickness 0.1524)
				)
				(justify mirror)
			)
		)
		(property "Device Type" "C0201H13"
			(at 2.8321 -3.2639 180)
			(unlocked yes)
			(layer "B.Fab")
			(hide yes)
			(effects
				(font
					(size 1.016 1.016)
					(thickness 0.1524)
				)
				(justify mirror)
			)
		)
		(duplicate_pad_numbers_are_jumpers no)
		(fp_rect
			(start 0.2794 0.6477)
			(end -0.2794 -0.6477)
			(stroke
				(width 0)
				(type default)
			)
			(fill no)
			(layer "B.CrtYd")
		)
		(fp_rect
			(start 0.2794 0.6477)
			(end -0.2794 -0.6477)
			(stroke
				(width 0)
				(type default)
			)
			(fill no)
			(layer "B.Fab")
		)
		(pad "1" smd custom
			(at 0 -0.2794)
			(size 0.0762 0.0762)
			(layers "B.Cu" "B.Mask" "B.Paste")
			(net "PHY_DPB_TO_SCC_16_DP")
			(options
				(clearance outline)
				(anchor circle)
			)
			(primitives
				(gr_poly
					(pts
						(arc
							(start 0.1524 0.127)
							(mid 0.137521 0.162921)
							(end 0.1016 0.1778)
						)
						(arc
							(start -0.1016 0.1778)
							(mid -0.137521 0.162921)
							(end -0.1524 0.127)
						)
						(arc
							(start -0.1524 -0.127)
							(mid -0.137521 -0.162921)
							(end -0.1016 -0.1778)
						)
						(arc
							(start 0.1016 -0.1778)
							(mid 0.137521 -0.162921)
							(end 0.1524 -0.127)
						)
					)
					(width 0)
					(fill yes)
				)
			)
		)
		(pad "2" smd custom
			(at 0 0.2794)
			(size 0.0762 0.0762)
			(layers "B.Cu" "B.Mask" "B.Paste")
			(net "PHY_DPB_TO_SCC_C_16_DP")
			(options
				(clearance outline)
				(anchor circle)
			)
			(primitives
				(gr_poly
					(pts
						(arc
							(start 0.1524 0.127)
							(mid 0.137521 0.162921)
							(end 0.1016 0.1778)
						)
						(arc
							(start -0.1016 0.1778)
							(mid -0.137521 0.162921)
							(end -0.1524 0.127)
						)
						(arc
							(start -0.1524 -0.127)
							(mid -0.137521 -0.162921)
							(end -0.1016 -0.1778)
						)
						(arc
							(start 0.1016 -0.1778)
							(mid 0.137521 -0.162921)
							(end 0.1524 -0.127)
						)
					)
					(width 0)
					(fill yes)
				)
			)
		)
	)
	(footprint ""
		(layer "B.Cu")
		(at 173.838108 -36.91001 -90)
		(property "Reference" "C446"
			(at 0 0 90)
			(layer "B.SilkS")
			(hide yes)
			(effects
				(font
					(size 1.27 1.27)
				)
				(justify mirror)
			)
		)
		(property "Value" "SC1KP50V2KX-1GP"
			(at -1.1811 -2.7051 270)
			(unlocked yes)
			(layer "B.Fab")
			(hide yes)
			(effects
				(font
					(size 1.016 1.016)
					(thickness 0.1524)
				)
				(justify mirror)
			)
		)
		(property "Device Type" "C402H22"
			(at -1.1811 -4.2291 270)
			(unlocked yes)
			(layer "B.Fab")
			(hide yes)
			(effects
				(font
					(size 1.016 1.016)
					(thickness 0.1524)
				)
				(justify mirror)
			)
		)
		(duplicate_pad_numbers_are_jumpers no)
		(fp_rect
			(start 0.4318 0.9525)
			(end -0.4318 -0.9525)
			(stroke
				(width 0)
				(type default)
			)
			(fill no)
			(layer "B.CrtYd")
		)
		(fp_rect
			(start 0.4318 0.9525)
			(end -0.4318 -0.9525)
			(stroke
				(width 0)
				(type default)
			)
			(fill no)
			(layer "B.Fab")
		)
		(pad "1" smd custom
			(at 0 -0.4445 90)
			(size 0.1524 0.1524)
			(layers "B.Cu" "B.Mask" "B.Paste")
			(net "P0V975")
			(options
				(clearance outline)
				(anchor circle)
			)
			(primitives
				(gr_poly
					(pts
						(arc
							(start 0.3048 0.2032)
							(mid 0.275042 0.275042)
							(end 0.2032 0.3048)
						)
						(arc
							(start -0.2032 0.3048)
							(mid -0.275042 0.275042)
							(end -0.3048 0.2032)
						)
						(arc
							(start -0.3048 -0.2032)
							(mid -0.275042 -0.275042)
							(end -0.2032 -0.3048)
						)
						(arc
							(start 0.2032 -0.3048)
							(mid 0.275042 -0.275042)
							(end 0.3048 -0.2032)
						)
					)
					(width 0)
					(fill yes)
				)
			)
		)
		(pad "2" smd custom
			(at 0 0.4445 90)
			(size 0.1524 0.1524)
			(layers "B.Cu" "B.Mask" "B.Paste")
			(net "GND")
			(options
				(clearance outline)
				(anchor circle)
			)
			(primitives
				(gr_poly
					(pts
						(arc
							(start 0.3048 0.2032)
							(mid 0.275042 0.275042)
							(end 0.2032 0.3048)
						)
						(arc
							(start -0.2032 0.3048)
							(mid -0.275042 0.275042)
							(end -0.3048 0.2032)
						)
						(arc
							(start -0.3048 -0.2032)
							(mid -0.275042 -0.275042)
							(end -0.2032 -0.3048)
						)
						(arc
							(start 0.2032 -0.3048)
							(mid 0.275042 -0.275042)
							(end 0.3048 -0.2032)
						)
					)
					(width 0)
					(fill yes)
				)
			)
		)
	)
)
